(kicad_pcb
	(version 20260206)
	(generator "pcbnew")
	(generator_version "10.0")
	(general
		(thickness 1.6)
		(legacy_teardrops no)
	)
	(paper "A4")
	(title_block
		(title "03242023_DA0F0TMBIJ0_F0T_Motherboard_J_brd_V01_OCP.brd")
		(comment 1 "Grand Teton / footprints 442-448 of 6105")
	)
	(layers
		(0 "F.Cu" signal "TOP")
		(4 "In1.Cu" signal "GND")
		(6 "In2.Cu" signal "IN1")
		(8 "In3.Cu" signal "GND1")
		(10 "In4.Cu" signal "IN2")
		(12 "In5.Cu" signal "GND2")
		(14 "In6.Cu" signal "IN3")
		(16 "In7.Cu" signal "GND3")
		(18 "In8.Cu" signal "VCC")
		(20 "In9.Cu" signal "VCC1")
		(22 "In10.Cu" signal "GND4")
		(24 "In11.Cu" signal "IN4")
		(26 "In12.Cu" signal "GND5")
		(28 "In13.Cu" signal "IN5")
		(30 "In14.Cu" signal "GND6")
		(32 "In15.Cu" signal "IN6")
		(34 "In16.Cu" signal "GND7")
		(2 "B.Cu" signal "BOTTOM")
		(9 "F.Adhes" user "F.Adhesive")
		(11 "B.Adhes" user "B.Adhesive")
		(13 "F.Paste" user "Package Geometry/Pastemask Top")
		(15 "B.Paste" user "Package Geometry/Pastemask Bottom")
		(5 "F.SilkS" user "Ref Des/Silkscreen Top")
		(7 "B.SilkS" user "Ref Des/Silkscreen Bottom")
		(1 "F.Mask" user "Board Geometry/Soldermask Top")
		(3 "B.Mask" user "Board Geometry/Soldermask Bottom")
		(17 "Dwgs.User" user "User.Drawings")
		(19 "Cmts.User" user "User.Comments")
		(21 "Eco1.User" user "User.Eco1")
		(23 "Eco2.User" user "User.Eco2")
		(25 "Edge.Cuts" user "Board Geometry/Outline")
		(27 "Margin" user)
		(31 "F.CrtYd" user "Package Geometry/Place Bound Top")
		(29 "B.CrtYd" user "Package Geometry/Place Bound Bottom")
		(35 "F.Fab" user "Ref Des/Assembly Top")
		(33 "B.Fab" user "Ref Des/Assembly Bottom")
	)
	(footprint ""
		(layer "F.Cu")
		(at 75.546458 -21.839682 180)
		(property "Reference" "PR3823"
			(at 0 0 180)
			(layer "F.SilkS")
			(hide yes)
			(effects
				(font
					(size 1.27 1.27)
				)
			)
		)
		(property "Value" ""
			(at 0 0 180)
			(layer "F.Fab")
			(effects
				(font
					(size 1.27 1.27)
				)
			)
		)
		(duplicate_pad_numbers_are_jumpers no)
		(fp_line
			(start 0.7874 0.4064)
			(end -0.7874 0.4064)
			(stroke
				(width 0.1524)
				(type default)
			)
			(layer "F.SilkS")
		)
		(fp_line
			(start 0.7874 -0.4064)
			(end 0.7874 0.4064)
			(stroke
				(width 0.1524)
				(type default)
			)
			(layer "F.SilkS")
		)
		(fp_line
			(start -0.7874 0.4064)
			(end -0.7874 -0.4064)
			(stroke
				(width 0.1524)
				(type default)
			)
			(layer "F.SilkS")
		)
		(fp_line
			(start -0.7874 -0.4064)
			(end 0.7874 -0.4064)
			(stroke
				(width 0.1524)
				(type default)
			)
			(layer "F.SilkS")
		)
		(fp_line
			(start 0.67945 0.3048)
			(end 0.120396 0.3048)
			(stroke
				(width 0.1)
				(type default)
			)
			(layer "F.Fab")
		)
		(fp_line
			(start 0.67945 -0.3048)
			(end 0.67945 0.3048)
			(stroke
				(width 0.1)
				(type default)
			)
			(layer "F.Fab")
		)
		(fp_line
			(start 0.12065 -0.2794)
			(end 0.12065 -0.3048)
			(stroke
				(width 0.1)
				(type default)
			)
			(layer "F.Fab")
		)
		(fp_line
			(start 0.12065 -0.3048)
			(end 0.67945 -0.3048)
			(stroke
				(width 0.1)
				(type default)
			)
			(layer "F.Fab")
		)
		(fp_line
			(start 0.120396 0.3048)
			(end 0.120396 0.2794)
			(stroke
				(width 0.1)
				(type default)
			)
			(layer "F.Fab")
		)
		(fp_line
			(start 0.120396 0.2794)
			(end -0.12065 0.2794)
			(stroke
				(width 0.1)
				(type default)
			)
			(layer "F.Fab")
		)
		(fp_line
			(start -0.12065 0.3048)
			(end -0.67945 0.3048)
			(stroke
				(width 0.1)
				(type default)
			)
			(layer "F.Fab")
		)
		(fp_line
			(start -0.12065 0.2794)
			(end -0.12065 0.3048)
			(stroke
				(width 0.1)
				(type default)
			)
			(layer "F.Fab")
		)
		(fp_line
			(start -0.12065 -0.2794)
			(end 0.12065 -0.2794)
			(stroke
				(width 0.1)
				(type default)
			)
			(layer "F.Fab")
		)
		(fp_line
			(start -0.12065 -0.305054)
			(end -0.12065 -0.2794)
			(stroke
				(width 0.1)
				(type default)
			)
			(layer "F.Fab")
		)
		(fp_line
			(start -0.67945 0.3048)
			(end -0.67945 -0.305054)
			(stroke
				(width 0.1)
				(type default)
			)
			(layer "F.Fab")
		)
		(fp_line
			(start -0.67945 -0.305054)
			(end -0.12065 -0.305054)
			(stroke
				(width 0.1)
				(type default)
			)
			(layer "F.Fab")
		)
		(pad "1" smd circle
			(at -0.40005 0 180)
			(size 0 0)
			(layers "F.Cu" "F.Mask" "F.Paste")
			(net "P12V_OCP_SENSE_2")
		)
		(pad "2" smd circle
			(at 0.40005 0 180)
			(size 0 0)
			(layers "F.Cu" "F.Mask" "F.Paste")
			(net "GND")
		)
	)
	(footprint ""
		(layer "F.Cu")
		(at 400.31289 -408.517344 -90)
		(property "Reference" "C888"
			(at 0 0 270)
			(layer "F.SilkS")
			(hide yes)
			(effects
				(font
					(size 1.27 1.27)
				)
			)
		)
		(property "Value" ""
			(at 0 0 270)
			(layer "F.Fab")
			(effects
				(font
					(size 1.27 1.27)
				)
			)
		)
		(duplicate_pad_numbers_are_jumpers no)
		(fp_line
			(start -0.299974 0.150114)
			(end -0.299974 -0.150114)
			(stroke
				(width 0.1)
				(type default)
			)
			(layer "F.Fab")
		)
		(fp_line
			(start 0.299974 0.150114)
			(end -0.299974 0.150114)
			(stroke
				(width 0.1)
				(type default)
			)
			(layer "F.Fab")
		)
		(fp_line
			(start -0.299974 -0.150114)
			(end 0.299974 -0.150114)
			(stroke
				(width 0.1)
				(type default)
			)
			(layer "F.Fab")
		)
		(fp_line
			(start 0.299974 -0.150114)
			(end 0.299974 0.150114)
			(stroke
				(width 0.1)
				(type default)
			)
			(layer "F.Fab")
		)
		(pad "1" smd rect
			(at -0.2667 0 270)
			(size 0.3048 0.381)
			(layers "F.Cu" "F.Mask" "F.Paste")
			(net "P5E_CPU0_PE3_TX_C_DN<6>")
		)
		(pad "2" smd rect
			(at 0.2667 0 270)
			(size 0.3048 0.381)
			(layers "F.Cu" "F.Mask" "F.Paste")
			(net "P5E_CPU0_PE3_TX_DN<6>")
		)
	)
	(footprint ""
		(layer "F.Cu")
		(at 104.104186 -40.935148)
		(property "Reference" "C1821"
			(at 0 0 0)
			(layer "F.SilkS")
			(hide yes)
			(effects
				(font
					(size 1.27 1.27)
				)
			)
		)
		(property "Value" ""
			(at 0 0 0)
			(layer "F.Fab")
			(effects
				(font
					(size 1.27 1.27)
				)
			)
		)
		(duplicate_pad_numbers_are_jumpers no)
		(fp_line
			(start -0.7874 -0.4064)
			(end 0.7874 -0.4064)
			(stroke
				(width 0.1524)
				(type default)
			)
			(layer "F.SilkS")
		)
		(fp_line
			(start -0.7874 0.4064)
			(end -0.7874 -0.4064)
			(stroke
				(width 0.1524)
				(type default)
			)
			(layer "F.SilkS")
		)
		(fp_line
			(start 0.7874 -0.4064)
			(end 0.7874 0.4064)
			(stroke
				(width 0.1524)
				(type default)
			)
			(layer "F.SilkS")
		)
		(fp_line
			(start 0.7874 0.4064)
			(end -0.7874 0.4064)
			(stroke
				(width 0.1524)
				(type default)
			)
			(layer "F.SilkS")
		)
		(fp_line
			(start -0.67945 -0.305054)
			(end -0.12065 -0.305054)
			(stroke
				(width 0.1)
				(type default)
			)
			(layer "F.Fab")
		)
		(fp_line
			(start -0.67945 0.3048)
			(end -0.67945 -0.305054)
			(stroke
				(width 0.1)
				(type default)
			)
			(layer "F.Fab")
		)
		(fp_line
			(start -0.12065 -0.305054)
			(end -0.12065 -0.2794)
			(stroke
				(width 0.1)
				(type default)
			)
			(layer "F.Fab")
		)
		(fp_line
			(start -0.12065 -0.2794)
			(end 0.12065 -0.2794)
			(stroke
				(width 0.1)
				(type default)
			)
			(layer "F.Fab")
		)
		(fp_line
			(start -0.12065 0.2794)
			(end -0.12065 0.3048)
			(stroke
				(width 0.1)
				(type default)
			)
			(layer "F.Fab")
		)
		(fp_line
			(start -0.12065 0.3048)
			(end -0.67945 0.3048)
			(stroke
				(width 0.1)
				(type default)
			)
			(layer "F.Fab")
		)
		(fp_line
			(start 0.120396 0.2794)
			(end -0.12065 0.2794)
			(stroke
				(width 0.1)
				(type default)
			)
			(layer "F.Fab")
		)
		(fp_line
			(start 0.120396 0.3048)
			(end 0.120396 0.2794)
			(stroke
				(width 0.1)
				(type default)
			)
			(layer "F.Fab")
		)
		(fp_line
			(start 0.12065 -0.3048)
			(end 0.67945 -0.3048)
			(stroke
				(width 0.1)
				(type default)
			)
			(layer "F.Fab")
		)
		(fp_line
			(start 0.12065 -0.2794)
			(end 0.12065 -0.3048)
			(stroke
				(width 0.1)
				(type default)
			)
			(layer "F.Fab")
		)
		(fp_line
			(start 0.67945 -0.3048)
			(end 0.67945 0.3048)
			(stroke
				(width 0.1)
				(type default)
			)
			(layer "F.Fab")
		)
		(fp_line
			(start 0.67945 0.3048)
			(end 0.120396 0.3048)
			(stroke
				(width 0.1)
				(type default)
			)
			(layer "F.Fab")
		)
		(pad "1" smd circle
			(at -0.40005 0)
			(size 0 0)
			(layers "F.Cu" "F.Mask" "F.Paste")
			(net "P3V3_AUX")
		)
		(pad "2" smd circle
			(at 0.40005 0)
			(size 0 0)
			(layers "F.Cu" "F.Mask" "F.Paste")
			(net "GND")
		)
	)
	(footprint ""
		(layer "F.Cu")
		(at 224.21215 -48.78197 180)
		(property "Reference" "R2426"
			(at 0 0 180)
			(layer "F.SilkS")
			(hide yes)
			(effects
				(font
					(size 1.27 1.27)
				)
			)
		)
		(property "Value" ""
			(at 0 0 180)
			(layer "F.Fab")
			(effects
				(font
					(size 1.27 1.27)
				)
			)
		)
		(duplicate_pad_numbers_are_jumpers no)
		(fp_line
			(start 0.7874 0.4064)
			(end -0.7874 0.4064)
			(stroke
				(width 0.1524)
				(type default)
			)
			(layer "F.SilkS")
		)
		(fp_line
			(start 0.7874 -0.4064)
			(end 0.7874 0.4064)
			(stroke
				(width 0.1524)
				(type default)
			)
			(layer "F.SilkS")
		)
		(fp_line
			(start -0.7874 0.4064)
			(end -0.7874 -0.4064)
			(stroke
				(width 0.1524)
				(type default)
			)
			(layer "F.SilkS")
		)
		(fp_line
			(start -0.7874 -0.4064)
			(end 0.7874 -0.4064)
			(stroke
				(width 0.1524)
				(type default)
			)
			(layer "F.SilkS")
		)
		(fp_line
			(start 0.67945 0.3048)
			(end 0.120396 0.3048)
			(stroke
				(width 0.1)
				(type default)
			)
			(layer "F.Fab")
		)
		(fp_line
			(start 0.67945 -0.3048)
			(end 0.67945 0.3048)
			(stroke
				(width 0.1)
				(type default)
			)
			(layer "F.Fab")
		)
		(fp_line
			(start 0.12065 -0.2794)
			(end 0.12065 -0.3048)
			(stroke
				(width 0.1)
				(type default)
			)
			(layer "F.Fab")
		)
		(fp_line
			(start 0.12065 -0.3048)
			(end 0.67945 -0.3048)
			(stroke
				(width 0.1)
				(type default)
			)
			(layer "F.Fab")
		)
		(fp_line
			(start 0.120396 0.3048)
			(end 0.120396 0.2794)
			(stroke
				(width 0.1)
				(type default)
			)
			(layer "F.Fab")
		)
		(fp_line
			(start 0.120396 0.2794)
			(end -0.12065 0.2794)
			(stroke
				(width 0.1)
				(type default)
			)
			(layer "F.Fab")
		)
		(fp_line
			(start -0.12065 0.3048)
			(end -0.67945 0.3048)
			(stroke
				(width 0.1)
				(type default)
			)
			(layer "F.Fab")
		)
		(fp_line
			(start -0.12065 0.2794)
			(end -0.12065 0.3048)
			(stroke
				(width 0.1)
				(type default)
			)
			(layer "F.Fab")
		)
		(fp_line
			(start -0.12065 -0.2794)
			(end 0.12065 -0.2794)
			(stroke
				(width 0.1)
				(type default)
			)
			(layer "F.Fab")
		)
		(fp_line
			(start -0.12065 -0.305054)
			(end -0.12065 -0.2794)
			(stroke
				(width 0.1)
				(type default)
			)
			(layer "F.Fab")
		)
		(fp_line
			(start -0.67945 0.3048)
			(end -0.67945 -0.305054)
			(stroke
				(width 0.1)
				(type default)
			)
			(layer "F.Fab")
		)
		(fp_line
			(start -0.67945 -0.305054)
			(end -0.12065 -0.305054)
			(stroke
				(width 0.1)
				(type default)
			)
			(layer "F.Fab")
		)
		(pad "1" smd circle
			(at -0.40005 0 180)
			(size 0 0)
			(layers "F.Cu" "F.Mask" "F.Paste")
			(net "E1S_0_PERST1_CLKREQ_N")
		)
		(pad "2" smd circle
			(at 0.40005 0 180)
			(size 0 0)
			(layers "F.Cu" "F.Mask" "F.Paste")
			(net "GND")
		)
	)
	(footprint ""
		(layer "F.Cu")
		(at 24.768556 -130.26898 180)
		(property "Reference" "PR665"
			(at 0 0 180)
			(layer "F.SilkS")
			(hide yes)
			(effects
				(font
					(size 1.27 1.27)
				)
			)
		)
		(property "Value" ""
			(at 0 0 180)
			(layer "F.Fab")
			(effects
				(font
					(size 1.27 1.27)
				)
			)
		)
		(duplicate_pad_numbers_are_jumpers no)
		(fp_line
			(start 0.7874 0.4064)
			(end -0.7874 0.4064)
			(stroke
				(width 0.1524)
				(type default)
			)
			(layer "F.SilkS")
		)
		(fp_line
			(start 0.7874 -0.4064)
			(end 0.7874 0.4064)
			(stroke
				(width 0.1524)
				(type default)
			)
			(layer "F.SilkS")
		)
		(fp_line
			(start -0.7874 0.4064)
			(end -0.7874 -0.4064)
			(stroke
				(width 0.1524)
				(type default)
			)
			(layer "F.SilkS")
		)
		(fp_line
			(start -0.7874 -0.4064)
			(end 0.7874 -0.4064)
			(stroke
				(width 0.1524)
				(type default)
			)
			(layer "F.SilkS")
		)
		(fp_line
			(start 0.67945 0.3048)
			(end 0.120396 0.3048)
			(stroke
				(width 0.1)
				(type default)
			)
			(layer "F.Fab")
		)
		(fp_line
			(start 0.67945 -0.3048)
			(end 0.67945 0.3048)
			(stroke
				(width 0.1)
				(type default)
			)
			(layer "F.Fab")
		)
		(fp_line
			(start 0.12065 -0.2794)
			(end 0.12065 -0.3048)
			(stroke
				(width 0.1)
				(type default)
			)
			(layer "F.Fab")
		)
		(fp_line
			(start 0.12065 -0.3048)
			(end 0.67945 -0.3048)
			(stroke
				(width 0.1)
				(type default)
			)
			(layer "F.Fab")
		)
		(fp_line
			(start 0.120396 0.3048)
			(end 0.120396 0.2794)
			(stroke
				(width 0.1)
				(type default)
			)
			(layer "F.Fab")
		)
		(fp_line
			(start 0.120396 0.2794)
			(end -0.12065 0.2794)
			(stroke
				(width 0.1)
				(type default)
			)
			(layer "F.Fab")
		)
		(fp_line
			(start -0.12065 0.3048)
			(end -0.67945 0.3048)
			(stroke
				(width 0.1)
				(type default)
			)
			(layer "F.Fab")
		)
		(fp_line
			(start -0.12065 0.2794)
			(end -0.12065 0.3048)
			(stroke
				(width 0.1)
				(type default)
			)
			(layer "F.Fab")
		)
		(fp_line
			(start -0.12065 -0.2794)
			(end 0.12065 -0.2794)
			(stroke
				(width 0.1)
				(type default)
			)
			(layer "F.Fab")
		)
		(fp_line
			(start -0.12065 -0.305054)
			(end -0.12065 -0.2794)
			(stroke
				(width 0.1)
				(type default)
			)
			(layer "F.Fab")
		)
		(fp_line
			(start -0.67945 0.3048)
			(end -0.67945 -0.305054)
			(stroke
				(width 0.1)
				(type default)
			)
			(layer "F.Fab")
		)
		(fp_line
			(start -0.67945 -0.305054)
			(end -0.12065 -0.305054)
			(stroke
				(width 0.1)
				(type default)
			)
			(layer "F.Fab")
		)
		(pad "1" smd circle
			(at -0.40005 0 180)
			(size 0 0)
			(layers "F.Cu" "F.Mask" "F.Paste")
			(net "PVCCINFAON_CPU1_ATSEN")
		)
		(pad "2" smd circle
			(at 0.40005 0 180)
			(size 0 0)
			(layers "F.Cu" "F.Mask" "F.Paste")
			(net "GND")
		)
	)
	(footprint ""
		(layer "F.Cu")
		(at 198.41464 -68.026788)
		(property "Reference" "PC2203"
			(at 0 0 0)
			(layer "F.SilkS")
			(hide yes)
			(effects
				(font
					(size 1.27 1.27)
				)
			)
		)
		(property "Value" ""
			(at 0 0 0)
			(layer "F.Fab")
			(effects
				(font
					(size 1.27 1.27)
				)
			)
		)
		(duplicate_pad_numbers_are_jumpers no)
		(fp_line
			(start -0.7874 -0.4064)
			(end 0.7874 -0.4064)
			(stroke
				(width 0.1524)
				(type default)
			)
			(layer "F.SilkS")
		)
		(fp_line
			(start -0.7874 0.4064)
			(end -0.7874 -0.4064)
			(stroke
				(width 0.1524)
				(type default)
			)
			(layer "F.SilkS")
		)
		(fp_line
			(start 0.7874 -0.4064)
			(end 0.7874 0.4064)
			(stroke
				(width 0.1524)
				(type default)
			)
			(layer "F.SilkS")
		)
		(fp_line
			(start 0.7874 0.4064)
			(end -0.7874 0.4064)
			(stroke
				(width 0.1524)
				(type default)
			)
			(layer "F.SilkS")
		)
		(fp_line
			(start -0.67945 -0.305054)
			(end -0.12065 -0.305054)
			(stroke
				(width 0.1)
				(type default)
			)
			(layer "F.Fab")
		)
		(fp_line
			(start -0.67945 0.3048)
			(end -0.67945 -0.305054)
			(stroke
				(width 0.1)
				(type default)
			)
			(layer "F.Fab")
		)
		(fp_line
			(start -0.12065 -0.305054)
			(end -0.12065 -0.2794)
			(stroke
				(width 0.1)
				(type default)
			)
			(layer "F.Fab")
		)
		(fp_line
			(start -0.12065 -0.2794)
			(end 0.12065 -0.2794)
			(stroke
				(width 0.1)
				(type default)
			)
			(layer "F.Fab")
		)
		(fp_line
			(start -0.12065 0.2794)
			(end -0.12065 0.3048)
			(stroke
				(width 0.1)
				(type default)
			)
			(layer "F.Fab")
		)
		(fp_line
			(start -0.12065 0.3048)
			(end -0.67945 0.3048)
			(stroke
				(width 0.1)
				(type default)
			)
			(layer "F.Fab")
		)
		(fp_line
			(start 0.120396 0.2794)
			(end -0.12065 0.2794)
			(stroke
				(width 0.1)
				(type default)
			)
			(layer "F.Fab")
		)
		(fp_line
			(start 0.120396 0.3048)
			(end 0.120396 0.2794)
			(stroke
				(width 0.1)
				(type default)
			)
			(layer "F.Fab")
		)
		(fp_line
			(start 0.12065 -0.3048)
			(end 0.67945 -0.3048)
			(stroke
				(width 0.1)
				(type default)
			)
			(layer "F.Fab")
		)
		(fp_line
			(start 0.12065 -0.2794)
			(end 0.12065 -0.3048)
			(stroke
				(width 0.1)
				(type default)
			)
			(layer "F.Fab")
		)
		(fp_line
			(start 0.67945 -0.3048)
			(end 0.67945 0.3048)
			(stroke
				(width 0.1)
				(type default)
			)
			(layer "F.Fab")
		)
		(fp_line
			(start 0.67945 0.3048)
			(end 0.120396 0.3048)
			(stroke
				(width 0.1)
				(type default)
			)
			(layer "F.Fab")
		)
		(pad "1" smd circle
			(at -0.40005 0)
			(size 0 0)
			(layers "F.Cu" "F.Mask" "F.Paste")
			(net "P3V3_E1S_GATE_0_PU293")
		)
		(pad "2" smd circle
			(at 0.40005 0)
			(size 0 0)
			(layers "F.Cu" "F.Mask" "F.Paste")
			(net "GND")
		)
	)
	(footprint ""
		(layer "F.Cu")
		(at 140.00988 -46.954948 180)
		(property "Reference" "R3298"
			(at 0 0 180)
			(layer "F.SilkS")
			(hide yes)
			(effects
				(font
					(size 1.27 1.27)
				)
			)
		)
		(property "Value" ""
			(at 0 0 180)
			(layer "F.Fab")
			(effects
				(font
					(size 1.27 1.27)
				)
			)
		)
		(duplicate_pad_numbers_are_jumpers no)
		(fp_line
			(start 0.7874 0.4064)
			(end -0.7874 0.4064)
			(stroke
				(width 0.1524)
				(type default)
			)
			(layer "F.SilkS")
		)
		(fp_line
			(start 0.7874 -0.4064)
			(end 0.7874 0.4064)
			(stroke
				(width 0.1524)
				(type default)
			)
			(layer "F.SilkS")
		)
		(fp_line
			(start -0.7874 0.4064)
			(end -0.7874 -0.4064)
			(stroke
				(width 0.1524)
				(type default)
			)
			(layer "F.SilkS")
		)
		(fp_line
			(start -0.7874 -0.4064)
			(end 0.7874 -0.4064)
			(stroke
				(width 0.1524)
				(type default)
			)
			(layer "F.SilkS")
		)
		(fp_line
			(start 0.67945 0.3048)
			(end 0.120396 0.3048)
			(stroke
				(width 0.1)
				(type default)
			)
			(layer "F.Fab")
		)
		(fp_line
			(start 0.67945 -0.3048)
			(end 0.67945 0.3048)
			(stroke
				(width 0.1)
				(type default)
			)
			(layer "F.Fab")
		)
		(fp_line
			(start 0.12065 -0.2794)
			(end 0.12065 -0.3048)
			(stroke
				(width 0.1)
				(type default)
			)
			(layer "F.Fab")
		)
		(fp_line
			(start 0.12065 -0.3048)
			(end 0.67945 -0.3048)
			(stroke
				(width 0.1)
				(type default)
			)
			(layer "F.Fab")
		)
		(fp_line
			(start 0.120396 0.3048)
			(end 0.120396 0.2794)
			(stroke
				(width 0.1)
				(type default)
			)
			(layer "F.Fab")
		)
		(fp_line
			(start 0.120396 0.2794)
			(end -0.12065 0.2794)
			(stroke
				(width 0.1)
				(type default)
			)
			(layer "F.Fab")
		)
		(fp_line
			(start -0.12065 0.3048)
			(end -0.67945 0.3048)
			(stroke
				(width 0.1)
				(type default)
			)
			(layer "F.Fab")
		)
		(fp_line
			(start -0.12065 0.2794)
			(end -0.12065 0.3048)
			(stroke
				(width 0.1)
				(type default)
			)
			(layer "F.Fab")
		)
		(fp_line
			(start -0.12065 -0.2794)
			(end 0.12065 -0.2794)
			(stroke
				(width 0.1)
				(type default)
			)
			(layer "F.Fab")
		)
		(fp_line
			(start -0.12065 -0.305054)
			(end -0.12065 -0.2794)
			(stroke
				(width 0.1)
				(type default)
			)
			(layer "F.Fab")
		)
		(fp_line
			(start -0.67945 0.3048)
			(end -0.67945 -0.305054)
			(stroke
				(width 0.1)
				(type default)
			)
			(layer "F.Fab")
		)
		(fp_line
			(start -0.67945 -0.305054)
			(end -0.12065 -0.305054)
			(stroke
				(width 0.1)
				(type default)
			)
			(layer "F.Fab")
		)
		(pad "1" smd circle
			(at -0.40005 0 180)
			(size 0 0)
			(layers "F.Cu" "F.Mask" "F.Paste")
			(net "P3V3_AUX")
		)
		(pad "2" smd circle
			(at 0.40005 0 180)
			(size 0 0)
			(layers "F.Cu" "F.Mask" "F.Paste")
			(net "HDD_ACTIVITY_BUF_N")
		)
	)
)
